(kicad_pcb
	(version 20260206)
	(generator "pcbnew")
	(generator_version "10.0")
	(general
		(thickness 1.6)
		(legacy_teardrops no)
	)
	(paper "A4")
	(title_block
		(title "9052_F0T_PDB_Converter_Brick_F_V03_1208_1600_OCP.brd")
		(comment 1 "Grand Teton / footprints 174-179 of 578")
	)
	(layers
		(0 "F.Cu" signal "TOP")
		(4 "In1.Cu" signal "GND")
		(6 "In2.Cu" signal "IN1")
		(8 "In3.Cu" signal "GND1")
		(10 "In4.Cu" signal "VCC")
		(12 "In5.Cu" signal "VCC1")
		(14 "In6.Cu" signal "GND2")
		(16 "In7.Cu" signal "IN2")
		(18 "In8.Cu" signal "GND3")
		(2 "B.Cu" signal "BOTTOM")
		(9 "F.Adhes" user "F.Adhesive")
		(11 "B.Adhes" user "B.Adhesive")
		(13 "F.Paste" user "Package Geometry/Pastemask Top")
		(15 "B.Paste" user "Package Geometry/Pastemask Bottom")
		(5 "F.SilkS" user "Ref Des/Silkscreen Top")
		(7 "B.SilkS" user "Ref Des/Silkscreen Bottom")
		(1 "F.Mask" user "Board Geometry/Soldermask Top")
		(3 "B.Mask" user "Board Geometry/Soldermask Bottom")
		(17 "Dwgs.User" user "User.Drawings")
		(19 "Cmts.User" user "User.Comments")
		(21 "Eco1.User" user "User.Eco1")
		(23 "Eco2.User" user "User.Eco2")
		(25 "Edge.Cuts" user "Board Geometry/Outline")
		(27 "Margin" user)
		(31 "F.CrtYd" user "Package Geometry/Place Bound Top")
		(29 "B.CrtYd" user "Package Geometry/Place Bound Bottom")
		(35 "F.Fab" user "Ref Des/Assembly Top")
		(33 "B.Fab" user "Ref Des/Assembly Bottom")
	)
	(footprint ""
		(layer "F.Cu")
		(at 271.018 -47.625 -90)
		(property "Reference" "PR209"
			(at 0 0 270)
			(layer "F.SilkS")
			(hide yes)
			(effects
				(font
					(size 1.27 1.27)
				)
			)
		)
		(property "Value" ""
			(at 0 0 270)
			(layer "F.Fab")
			(effects
				(font
					(size 1.27 1.27)
				)
			)
		)
		(duplicate_pad_numbers_are_jumpers no)
		(fp_line
			(start -0.7874 0.4064)
			(end -0.7874 -0.4064)
			(stroke
				(width 0.1524)
				(type default)
			)
			(layer "F.SilkS")
		)
		(fp_line
			(start 0.7874 0.4064)
			(end -0.7874 0.4064)
			(stroke
				(width 0.1524)
				(type default)
			)
			(layer "F.SilkS")
		)
		(fp_line
			(start -0.7874 -0.4064)
			(end 0.7874 -0.4064)
			(stroke
				(width 0.1524)
				(type default)
			)
			(layer "F.SilkS")
		)
		(fp_line
			(start 0.7874 -0.4064)
			(end 0.7874 0.4064)
			(stroke
				(width 0.1524)
				(type default)
			)
			(layer "F.SilkS")
		)
		(fp_line
			(start -0.67945 0.3048)
			(end -0.67945 -0.305054)
			(stroke
				(width 0.1)
				(type default)
			)
			(layer "F.Fab")
		)
		(fp_line
			(start -0.12065 0.3048)
			(end -0.67945 0.3048)
			(stroke
				(width 0.1)
				(type default)
			)
			(layer "F.Fab")
		)
		(fp_line
			(start 0.120396 0.3048)
			(end 0.120396 0.2794)
			(stroke
				(width 0.1)
				(type default)
			)
			(layer "F.Fab")
		)
		(fp_line
			(start 0.67945 0.3048)
			(end 0.120396 0.3048)
			(stroke
				(width 0.1)
				(type default)
			)
			(layer "F.Fab")
		)
		(fp_line
			(start -0.12065 0.2794)
			(end -0.12065 0.3048)
			(stroke
				(width 0.1)
				(type default)
			)
			(layer "F.Fab")
		)
		(fp_line
			(start 0.120396 0.2794)
			(end -0.12065 0.2794)
			(stroke
				(width 0.1)
				(type default)
			)
			(layer "F.Fab")
		)
		(fp_line
			(start -0.12065 -0.2794)
			(end 0.12065 -0.2794)
			(stroke
				(width 0.1)
				(type default)
			)
			(layer "F.Fab")
		)
		(fp_line
			(start 0.12065 -0.2794)
			(end 0.12065 -0.3048)
			(stroke
				(width 0.1)
				(type default)
			)
			(layer "F.Fab")
		)
		(fp_line
			(start 0.12065 -0.3048)
			(end 0.67945 -0.3048)
			(stroke
				(width 0.1)
				(type default)
			)
			(layer "F.Fab")
		)
		(fp_line
			(start 0.67945 -0.3048)
			(end 0.67945 0.3048)
			(stroke
				(width 0.1)
				(type default)
			)
			(layer "F.Fab")
		)
		(fp_line
			(start -0.67945 -0.305054)
			(end -0.12065 -0.305054)
			(stroke
				(width 0.1)
				(type default)
			)
			(layer "F.Fab")
		)
		(fp_line
			(start -0.12065 -0.305054)
			(end -0.12065 -0.2794)
			(stroke
				(width 0.1)
				(type default)
			)
			(layer "F.Fab")
		)
		(pad "1" smd circle
			(at -0.40005 0 270)
			(size 0 0)
			(layers "F.Cu" "F.Mask" "F.Paste")
			(net "GND_FIELD_SIGNAL")
		)
		(pad "2" smd circle
			(at 0.40005 0 270)
			(size 0 0)
			(layers "F.Cu" "F.Mask" "F.Paste")
			(net "P52V_HS1_CS")
		)
	)
	(footprint ""
		(layer "F.Cu")
		(at 264.541 -47.625 90)
		(property "Reference" "PC6"
			(at 0 0 90)
			(layer "F.SilkS")
			(hide yes)
			(effects
				(font
					(size 1.27 1.27)
				)
			)
		)
		(property "Value" ""
			(at 0 0 90)
			(layer "F.Fab")
			(effects
				(font
					(size 1.27 1.27)
				)
			)
		)
		(duplicate_pad_numbers_are_jumpers no)
		(fp_line
			(start 0.7874 -0.4064)
			(end 0.7874 0.4064)
			(stroke
				(width 0.1524)
				(type default)
			)
			(layer "F.SilkS")
		)
		(fp_line
			(start -0.7874 -0.4064)
			(end 0.7874 -0.4064)
			(stroke
				(width 0.1524)
				(type default)
			)
			(layer "F.SilkS")
		)
		(fp_line
			(start 0.7874 0.4064)
			(end -0.7874 0.4064)
			(stroke
				(width 0.1524)
				(type default)
			)
			(layer "F.SilkS")
		)
		(fp_line
			(start -0.7874 0.4064)
			(end -0.7874 -0.4064)
			(stroke
				(width 0.1524)
				(type default)
			)
			(layer "F.SilkS")
		)
		(fp_line
			(start -0.12065 -0.305054)
			(end -0.12065 -0.2794)
			(stroke
				(width 0.1)
				(type default)
			)
			(layer "F.Fab")
		)
		(fp_line
			(start -0.67945 -0.305054)
			(end -0.12065 -0.305054)
			(stroke
				(width 0.1)
				(type default)
			)
			(layer "F.Fab")
		)
		(fp_line
			(start 0.67945 -0.3048)
			(end 0.67945 0.3048)
			(stroke
				(width 0.1)
				(type default)
			)
			(layer "F.Fab")
		)
		(fp_line
			(start 0.12065 -0.3048)
			(end 0.67945 -0.3048)
			(stroke
				(width 0.1)
				(type default)
			)
			(layer "F.Fab")
		)
		(fp_line
			(start 0.12065 -0.2794)
			(end 0.12065 -0.3048)
			(stroke
				(width 0.1)
				(type default)
			)
			(layer "F.Fab")
		)
		(fp_line
			(start -0.12065 -0.2794)
			(end 0.12065 -0.2794)
			(stroke
				(width 0.1)
				(type default)
			)
			(layer "F.Fab")
		)
		(fp_line
			(start 0.120396 0.2794)
			(end -0.12065 0.2794)
			(stroke
				(width 0.1)
				(type default)
			)
			(layer "F.Fab")
		)
		(fp_line
			(start -0.12065 0.2794)
			(end -0.12065 0.3048)
			(stroke
				(width 0.1)
				(type default)
			)
			(layer "F.Fab")
		)
		(fp_line
			(start 0.67945 0.3048)
			(end 0.120396 0.3048)
			(stroke
				(width 0.1)
				(type default)
			)
			(layer "F.Fab")
		)
		(fp_line
			(start 0.120396 0.3048)
			(end 0.120396 0.2794)
			(stroke
				(width 0.1)
				(type default)
			)
			(layer "F.Fab")
		)
		(fp_line
			(start -0.12065 0.3048)
			(end -0.67945 0.3048)
			(stroke
				(width 0.1)
				(type default)
			)
			(layer "F.Fab")
		)
		(fp_line
			(start -0.67945 0.3048)
			(end -0.67945 -0.305054)
			(stroke
				(width 0.1)
				(type default)
			)
			(layer "F.Fab")
		)
		(pad "1" smd circle
			(at -0.40005 0 90)
			(size 0 0)
			(layers "F.Cu" "F.Mask" "F.Paste")
			(net "P52V_HS1_TEMP")
		)
		(pad "2" smd circle
			(at 0.40005 0 90)
			(size 0 0)
			(layers "F.Cu" "F.Mask" "F.Paste")
			(net "GND_FIELD_SIGNAL")
		)
	)
	(footprint ""
		(layer "F.Cu")
		(at 300.624494 -36.438586 90)
		(property "Reference" "PD7"
			(at -4.7244 -3.851148 90)
			(unlocked yes)
			(layer "F.SilkS")
			(effects
				(font
					(size 0.7874 0.5842)
					(thickness 0.1524)
				)
				(justify left)
			)
		)
		(property "Value" ""
			(at 0 0 90)
			(layer "F.Fab")
			(effects
				(font
					(size 1.27 1.27)
				)
			)
		)
		(duplicate_pad_numbers_are_jumpers no)
		(fp_line
			(start 5.4102 -3.109976)
			(end 4.783074 -3.109976)
			(stroke
				(width 0.1524)
				(type default)
			)
			(layer "F.SilkS")
		)
		(fp_line
			(start 5.313426 -3.109976)
			(end 5.313426 3.109976)
			(stroke
				(width 0.1524)
				(type default)
			)
			(layer "F.SilkS")
		)
		(fp_line
			(start 5.262626 -3.109976)
			(end 5.262626 3.109976)
			(stroke
				(width 0.1524)
				(type default)
			)
			(layer "F.SilkS")
		)
		(fp_line
			(start 5.211826 -3.109976)
			(end 5.211826 3.109976)
			(stroke
				(width 0.1524)
				(type default)
			)
			(layer "F.SilkS")
		)
		(fp_line
			(start 5.110226 -3.109976)
			(end 5.110226 3.109976)
			(stroke
				(width 0.1524)
				(type default)
			)
			(layer "F.SilkS")
		)
		(fp_line
			(start 5.008626 -3.109976)
			(end 5.008626 3.109976)
			(stroke
				(width 0.1524)
				(type default)
			)
			(layer "F.SilkS")
		)
		(fp_line
			(start 4.932426 -3.109976)
			(end 4.932426 3.109976)
			(stroke
				(width 0.1524)
				(type default)
			)
			(layer "F.SilkS")
		)
		(fp_line
			(start 4.805426 -3.109976)
			(end 4.805426 3.109976)
			(stroke
				(width 0.1524)
				(type default)
			)
			(layer "F.SilkS")
		)
		(fp_line
			(start 4.70535 -3.109976)
			(end 4.70535 3.109976)
			(stroke
				(width 0.1524)
				(type default)
			)
			(layer "F.SilkS")
		)
		(fp_line
			(start 4.70535 -3.109976)
			(end 4.70535 3.109976)
			(stroke
				(width 0.1524)
				(type default)
			)
			(layer "F.SilkS")
		)
		(fp_line
			(start 4.70535 -3.109976)
			(end 4.70535 3.109976)
			(stroke
				(width 0.1524)
				(type default)
			)
			(layer "F.SilkS")
		)
		(fp_line
			(start 4.695444 -3.109976)
			(end 4.695444 3.109976)
			(stroke
				(width 0.1524)
				(type default)
			)
			(layer "F.SilkS")
		)
		(fp_line
			(start 4.6101 -3.109976)
			(end 4.283202 -3.109976)
			(stroke
				(width 0.1524)
				(type default)
			)
			(layer "F.SilkS")
		)
		(fp_line
			(start 4.511802 -3.109976)
			(end 4.207002 -3.109976)
			(stroke
				(width 0.1524)
				(type default)
			)
			(layer "F.SilkS")
		)
		(fp_line
			(start 4.183126 -3.109976)
			(end 4.794504 -3.109976)
			(stroke
				(width 0.1524)
				(type default)
			)
			(layer "F.SilkS")
		)
		(fp_line
			(start -4.664456 -3.109976)
			(end 4.743704 -3.109976)
			(stroke
				(width 0.1524)
				(type default)
			)
			(layer "F.SilkS")
		)
		(fp_line
			(start -0.508 -1.016)
			(end 0.762 0)
			(stroke
				(width 0.1524)
				(type default)
			)
			(layer "F.SilkS")
		)
		(fp_line
			(start 0.762 0)
			(end 1.2192 0)
			(stroke
				(width 0.1524)
				(type default)
			)
			(layer "F.SilkS")
		)
		(fp_line
			(start 0.762 0)
			(end -0.508 1.016)
			(stroke
				(width 0.1524)
				(type default)
			)
			(layer "F.SilkS")
		)
		(fp_line
			(start -1.0668 0)
			(end -0.6096 0)
			(stroke
				(width 0.1524)
				(type default)
			)
			(layer "F.SilkS")
		)
		(fp_line
			(start -0.508 1.016)
			(end -0.508 -1.016)
			(stroke
				(width 0.1524)
				(type default)
			)
			(layer "F.SilkS")
		)
		(fp_line
			(start 0.762 1.27)
			(end 0.762 -1.27)
			(stroke
				(width 0.1524)
				(type default)
			)
			(layer "F.SilkS")
		)
		(fp_line
			(start 4.715002 3.035554)
			(end 4.7117 2.984754)
			(stroke
				(width 0.1524)
				(type default)
			)
			(layer "F.SilkS")
		)
		(fp_line
			(start 5.4102 3.109976)
			(end 5.4102 -3.109976)
			(stroke
				(width 0.1524)
				(type default)
			)
			(layer "F.SilkS")
		)
		(fp_line
			(start 4.794504 3.109976)
			(end 3.554984 3.109976)
			(stroke
				(width 0.1524)
				(type default)
			)
			(layer "F.SilkS")
		)
		(fp_line
			(start 4.769104 3.109976)
			(end -4.664456 3.109976)
			(stroke
				(width 0.1524)
				(type default)
			)
			(layer "F.SilkS")
		)
		(fp_line
			(start 4.743704 3.109976)
			(end 5.4102 3.109976)
			(stroke
				(width 0.1524)
				(type default)
			)
			(layer "F.SilkS")
		)
		(fp_line
			(start 4.743704 3.109976)
			(end 4.6101 3.109976)
			(stroke
				(width 0.1524)
				(type default)
			)
			(layer "F.SilkS")
		)
		(fp_line
			(start 4.156202 3.109976)
			(end 4.183126 3.109976)
			(stroke
				(width 0.1524)
				(type default)
			)
			(layer "F.SilkS")
		)
		(fp_line
			(start -4.664456 3.109976)
			(end -4.664456 -3.109976)
			(stroke
				(width 0.1524)
				(type default)
			)
			(layer "F.SilkS")
		)
		(fp_line
			(start 4.065016 -3.109976)
			(end 4.065016 3.109976)
			(stroke
				(width 0.1)
				(type default)
			)
			(layer "F.Fab")
		)
		(fp_line
			(start -4.065016 -3.109976)
			(end 4.065016 -3.109976)
			(stroke
				(width 0.1)
				(type default)
			)
			(layer "F.Fab")
		)
		(fp_line
			(start 4.065016 3.109976)
			(end -4.065016 3.109976)
			(stroke
				(width 0.1)
				(type default)
			)
			(layer "F.Fab")
		)
		(fp_line
			(start -4.065016 3.109976)
			(end -4.065016 -3.109976)
			(stroke
				(width 0.1)
				(type default)
			)
			(layer "F.Fab")
		)
		(fp_text user "+"
			(at -5.831586 -0.021844 270)
			(unlocked yes)
			(layer "F.SilkS")
			(effects
				(font
					(size 1.905 1.4224)
					(thickness 0.1524)
				)
				(justify left)
			)
		)
		(fp_text user "-"
			(at 6.741414 2.645156 270)
			(unlocked yes)
			(layer "F.SilkS")
			(effects
				(font
					(size 1.905 1.4224)
					(thickness 0.1524)
				)
				(justify left)
			)
		)
		(fp_text user "+"
			(at -4.5974 0.24765 270)
			(unlocked yes)
			(layer "F.Fab")
			(effects
				(font
					(size 1.905 1.4224)
					(thickness 0.1524)
				)
				(justify left)
			)
		)
		(fp_text user "-"
			(at 6.643624 0.40005 270)
			(unlocked yes)
			(layer "F.Fab")
			(effects
				(font
					(size 1.905 1.4224)
					(thickness 0.1524)
				)
				(justify left)
			)
		)
		(pad "A" smd rect
			(at -3.299968 0 270)
			(size 2.413 3.302)
			(layers "F.Cu" "F.Mask" "F.Paste")
			(net "GND")
		)
		(pad "C" smd rect
			(at 3.299968 0 270)
			(size 2.413 3.302)
			(layers "F.Cu" "F.Mask" "F.Paste")
			(net "P52V_1_FUSE_1")
		)
	)
	(footprint ""
		(layer "F.Cu")
		(at 68.072 -60.96)
		(property "Reference" "PC98"
			(at -1.27 -3.52933 0)
			(unlocked yes)
			(layer "F.SilkS")
			(effects
				(font
					(size 0.7874 0.5842)
					(thickness 0.1524)
				)
				(justify left)
			)
		)
		(property "Value" ""
			(at 0 0 0)
			(layer "F.Fab")
			(effects
				(font
					(size 1.27 1.27)
				)
			)
		)
		(duplicate_pad_numbers_are_jumpers no)
		(fp_line
			(start 5.2578 2.499868)
			(end -5.2578 2.499868)
			(stroke
				(width 0.1524)
				(type default)
			)
			(layer "F.SilkS")
		)
		(fp_circle
			(center 0 2.499868)
			(end 5.2578 2.499868)
			(stroke
				(width 0.1524)
				(type default)
			)
			(fill no)
			(layer "F.SilkS")
		)
		(fp_poly
			(pts
				(arc
					(start 5.2578 2.499868)
					(mid 0 7.757922)
					(end -5.2578 2.499868)
				)
			)
			(stroke
				(width 0)
				(type default)
			)
			(fill yes)
			(layer "F.SilkS")
		)
		(fp_circle
			(center 0 2.499868)
			(end 5.2578 2.499868)
			(stroke
				(width 0.1)
				(type default)
			)
			(fill no)
			(layer "F.Fab")
		)
		(pad "1" thru_hole rect
			(at 0 0 270)
			(size 1.524 1.524)
			(drill 1.016)
			(layers "*.Cu" "*.Mask")
			(remove_unused_layers no)
			(net "P12V_BRICK")
			(clearance 0)
			(padstack
				(mode front_inner_back)
				(layer "Inner"
					(shape circle)
					(size 1.524 1.524)
					(clearance 0)
				)
				(layer "B.Cu"
					(shape rect)
					(size 1.524 1.524)
					(clearance 0)
				)
			)
		)
		(pad "2" thru_hole circle
			(at 0 4.99999 270)
			(size 1.524 1.524)
			(drill 1.016)
			(layers "*.Cu" "*.Mask")
			(remove_unused_layers no)
			(net "GND")
			(clearance 0)
		)
	)
	(footprint ""
		(layer "F.Cu")
		(at 174.239174 -136.906 90)
		(property "Reference" "PC114"
			(at 6.19633 0.766826 0)
			(unlocked yes)
			(layer "F.SilkS")
			(effects
				(font
					(size 0.7874 0.5842)
					(thickness 0.1524)
				)
				(justify left)
			)
		)
		(property "Value" ""
			(at 0 0 90)
			(layer "F.Fab")
			(effects
				(font
					(size 1.27 1.27)
				)
			)
		)
		(duplicate_pad_numbers_are_jumpers no)
		(fp_line
			(start 5.2578 2.499868)
			(end -5.2578 2.499868)
			(stroke
				(width 0.1524)
				(type default)
			)
			(layer "F.SilkS")
		)
		(fp_circle
			(center 0 2.500122)
			(end 0 7.758176)
			(stroke
				(width 0.1524)
				(type default)
			)
			(fill no)
			(layer "F.SilkS")
		)
		(fp_poly
			(pts
				(arc
					(start 5.2578 2.499868)
					(mid 0 7.757922)
					(end -5.2578 2.499868)
				)
			)
			(stroke
				(width 0)
				(type default)
			)
			(fill yes)
			(layer "F.SilkS")
		)
		(fp_circle
			(center 0 2.500122)
			(end 0 7.758176)
			(stroke
				(width 0.1)
				(type default)
			)
			(fill no)
			(layer "F.Fab")
		)
		(pad "1" thru_hole rect
			(at 0 0)
			(size 1.5748 1.5748)
			(drill 1.0668)
			(layers "*.Cu" "*.Mask")
			(remove_unused_layers no)
			(net "P52V_HS_FILTER")
			(clearance 0)
			(padstack
				(mode front_inner_back)
				(layer "Inner"
					(shape circle)
					(size 1.5748 1.5748)
					(clearance 0)
				)
				(layer "B.Cu"
					(shape rect)
					(size 1.5748 1.5748)
					(clearance 0)
				)
			)
		)
		(pad "2" thru_hole circle
			(at 0 4.99999)
			(size 1.5748 1.5748)
			(drill 1.0668)
			(layers "*.Cu" "*.Mask")
			(remove_unused_layers no)
			(net "GND")
			(clearance 0)
		)
	)
	(footprint ""
		(layer "F.Cu")
		(at 279.027128 -36.358576)
		(property "Reference" "R145"
			(at 0 0 0)
			(layer "F.SilkS")
			(hide yes)
			(effects
				(font
					(size 1.27 1.27)
				)
			)
		)
		(property "Value" ""
			(at 0 0 0)
			(layer "F.Fab")
			(effects
				(font
					(size 1.27 1.27)
				)
			)
		)
		(duplicate_pad_numbers_are_jumpers no)
		(fp_line
			(start -0.7874 -0.4064)
			(end 0.7874 -0.4064)
			(stroke
				(width 0.1524)
				(type default)
			)
			(layer "F.SilkS")
		)
		(fp_line
			(start -0.7874 0.4064)
			(end -0.7874 -0.4064)
			(stroke
				(width 0.1524)
				(type default)
			)
			(layer "F.SilkS")
		)
		(fp_line
			(start 0.7874 -0.4064)
			(end 0.7874 0.4064)
			(stroke
				(width 0.1524)
				(type default)
			)
			(layer "F.SilkS")
		)
		(fp_line
			(start 0.7874 0.4064)
			(end -0.7874 0.4064)
			(stroke
				(width 0.1524)
				(type default)
			)
			(layer "F.SilkS")
		)
		(fp_line
			(start -0.67945 -0.305054)
			(end -0.12065 -0.305054)
			(stroke
				(width 0.1)
				(type default)
			)
			(layer "F.Fab")
		)
		(fp_line
			(start -0.67945 0.3048)
			(end -0.67945 -0.305054)
			(stroke
				(width 0.1)
				(type default)
			)
			(layer "F.Fab")
		)
		(fp_line
			(start -0.12065 -0.305054)
			(end -0.12065 -0.2794)
			(stroke
				(width 0.1)
				(type default)
			)
			(layer "F.Fab")
		)
		(fp_line
			(start -0.12065 -0.2794)
			(end 0.12065 -0.2794)
			(stroke
				(width 0.1)
				(type default)
			)
			(layer "F.Fab")
		)
		(fp_line
			(start -0.12065 0.2794)
			(end -0.12065 0.3048)
			(stroke
				(width 0.1)
				(type default)
			)
			(layer "F.Fab")
		)
		(fp_line
			(start -0.12065 0.3048)
			(end -0.67945 0.3048)
			(stroke
				(width 0.1)
				(type default)
			)
			(layer "F.Fab")
		)
		(fp_line
			(start 0.120396 0.2794)
			(end -0.12065 0.2794)
			(stroke
				(width 0.1)
				(type default)
			)
			(layer "F.Fab")
		)
		(fp_line
			(start 0.120396 0.3048)
			(end 0.120396 0.2794)
			(stroke
				(width 0.1)
				(type default)
			)
			(layer "F.Fab")
		)
		(fp_line
			(start 0.12065 -0.3048)
			(end 0.67945 -0.3048)
			(stroke
				(width 0.1)
				(type default)
			)
			(layer "F.Fab")
		)
		(fp_line
			(start 0.12065 -0.2794)
			(end 0.12065 -0.3048)
			(stroke
				(width 0.1)
				(type default)
			)
			(layer "F.Fab")
		)
		(fp_line
			(start 0.67945 -0.3048)
			(end 0.67945 0.3048)
			(stroke
				(width 0.1)
				(type default)
			)
			(layer "F.Fab")
		)
		(fp_line
			(start 0.67945 0.3048)
			(end 0.120396 0.3048)
			(stroke
				(width 0.1)
				(type default)
			)
			(layer "F.Fab")
		)
		(pad "1" smd circle
			(at -0.40005 0)
			(size 0 0)
			(layers "F.Cu" "F.Mask" "F.Paste")
			(net "SMB_P52V_HSC_SDA")
		)
		(pad "2" smd circle
			(at 0.40005 0)
			(size 0 0)
			(layers "F.Cu" "F.Mask" "F.Paste")
			(net "SMB_CM_HS1_3V3SB_DATO")
		)
	)
)
